(kicad_pcb
	(version 20221018)
	(generator pcbnew)
	(general
    (thickness 1.518)
  )
	(paper "A4")
	(title_block
    (title "Kria K26 Devboard")
    (date "2024-03-26")
    (rev "1.2.5")
    (comment 1 "www.antmicro.com")
    (comment 2 "Antmicro Ltd.")
		(comment 9 "footprints 174-181 of 660")
	)
	(layers
    (0 "F.Cu" mixed)
    (1 "In1.Cu" power)
    (2 "In2.Cu" mixed)
    (3 "In3.Cu" power)
    (4 "In4.Cu" mixed)
    (5 "In5.Cu" power)
    (6 "In6.Cu" mixed)
    (31 "B.Cu" power)
    (32 "B.Adhes" user "B.Adhesive")
    (33 "F.Adhes" user "F.Adhesive")
    (34 "B.Paste" user)
    (35 "F.Paste" user)
    (36 "B.SilkS" user "B.Silkscreen")
    (37 "F.SilkS" user "F.Silkscreen")
    (38 "B.Mask" user)
    (39 "F.Mask" user)
    (40 "Dwgs.User" user "User.Drawings")
    (41 "Cmts.User" user "User.Comments")
    (42 "Eco1.User" user "User.Eco1")
    (43 "Eco2.User" user "User.Eco2")
    (44 "Edge.Cuts" user)
    (45 "Margin" user)
    (46 "B.CrtYd" user "B.Courtyard")
    (47 "F.CrtYd" user "F.Courtyard")
    (48 "B.Fab" user)
    (49 "F.Fab" user)
  )
	(footprint "kria-k26-devboard-footprints:TSOT23-6" (layer "F.Cu")
    (at 187.1 132.9 90)
    (property "Author" "Antmicro")
    (property "License" "Apache-2.0")
    (property "MPN" "AP62301WU-7")
    (property "Manufacturer" "Diodes Incorporated")
    (property "Sheetfile" "dc-dc-conventers.kicad_sch")
    (property "Sheetname" "DC/DC conventers")
    (property "ki_description" "DC-DC Switching Synchronous Buck Regulator, Adjustable, 4.2V-18Vin, 0.8V-7V/3A out, TSOT-26-6")
    (property "ki_keywords" "SMT, PMIC, IC, VOLTAGE")
    (attr smd)
    (fp_text reference "U55" (at 1.71 -0.33 180) (layer "F.SilkS")
        (effects (font (size 0.7 0.7) (thickness 0.15)) (justify left bottom))
    )
    (fp_text value "AP62301_TSOT" (at -0.005 2.6 90) (layer "F.Fab") hide
        (effects (font (size 0.7 0.7) (thickness 0.15)) (justify left bottom))
    )
    (fp_text user "Author: Antmicro" (at -1.893 7.368 90) (layer "F.Fab") hide
        (effects (font (size 0.7 0.7) (thickness 0.15)) (justify left bottom))
    )
    (fp_text user "${REFERENCE}" (at -1.893 6.168 90) (layer "F.Fab") hide
        (effects (font (size 0.7 0.7) (thickness 0.15)) (justify left bottom))
    )
    (fp_text user "License: Apache-2.0" (at -1.893 4.967 90) (layer "F.Fab") hide
        (effects (font (size 0.7 0.7) (thickness 0.15)) (justify left bottom))
    )
    (fp_line (start -1.4805 0.725) (end -1.4795 -0.725)
      (stroke (width 0.15) (type solid)) (layer "F.SilkS"))
    (fp_line (start -1.4805 0.725) (end -1.3905 0.725)
      (stroke (width 0.15) (type solid)) (layer "F.SilkS"))
    (fp_line (start -1.4795 -0.725) (end -1.3905 -0.725)
      (stroke (width 0.15) (type solid)) (layer "F.SilkS"))
    (fp_line (start 1.479 0.73) (end 1.38 0.73)
      (stroke (width 0.15) (type solid)) (layer "F.SilkS"))
    (fp_line (start 1.48 -0.72) (end 1.38 -0.72)
      (stroke (width 0.15) (type solid)) (layer "F.SilkS"))
    (fp_line (start 1.48 -0.72) (end 1.479 0.73)
      (stroke (width 0.15) (type solid)) (layer "F.SilkS"))
    (fp_circle (center -1.499 1.236) (end -1.45 1.236)
      (stroke (width 0.15) (type solid)) (fill solid) (layer "F.SilkS"))
    (fp_rect (start -1.65 -1.61) (end 1.65 1.61)
      (stroke (width 0.05) (type solid)) (fill none) (layer "F.CrtYd"))
    (fp_line (start -1.527 -0.833) (end 1.523 -0.833)
      (stroke (width 0.15) (type solid)) (layer "F.Fab"))
    (fp_line (start -1.527 0.491) (end -1.527 -0.833)
      (stroke (width 0.15) (type solid)) (layer "F.Fab"))
    (fp_line (start -1.527 0.491) (end -1.102 0.916)
      (stroke (width 0.15) (type solid)) (layer "F.Fab"))
    (fp_line (start -1.102 0.916) (end 1.523 0.916)
      (stroke (width 0.15) (type solid)) (layer "F.Fab"))
    (fp_line (start 1.523 -0.833) (end 1.523 0.916)
      (stroke (width 0.15) (type solid)) (layer "F.Fab"))
    (pad "1" smd rect (at -0.952 1.18 90) (size 0.7 0.8) (layers "F.Cu" "F.Paste" "F.Mask")
      (net 1 "GND") (pinfunction "GND") (pintype "power_in"))
    (pad "2" smd rect (at -0.001 1.18 90) (size 0.7 0.8) (layers "F.Cu" "F.Paste" "F.Mask")
      (net 316 "/Power Supply/DC/DC conventers/SW_PL_1V2") (pinfunction "SW") (pintype "power_out"))
    (pad "3" smd rect (at 0.947 1.18 90) (size 0.7 0.8) (layers "F.Cu" "F.Paste" "F.Mask")
      (net 14 "/Power Supply/DC/DC conventers/DC_MAIN_BUS") (pinfunction "VIN") (pintype "power_in"))
    (pad "4" smd rect (at 0.947 -1.18 90) (size 0.7 0.8) (layers "F.Cu" "F.Paste" "F.Mask")
      (net 694 "Net-(U55-FB)") (pinfunction "FB") (pintype "input"))
    (pad "5" smd rect (at -0.001 -1.18 90) (size 0.7 0.8) (layers "F.Cu" "F.Paste" "F.Mask")
      (net 24 "/Power Supply/VCCOEN_PL_M2C") (pinfunction "EN") (pintype "input"))
    (pad "6" smd rect (at -0.952 -1.18 90) (size 0.7 0.8) (layers "F.Cu" "F.Paste" "F.Mask")
      (net 326 "Net-(U55-BST)") (pinfunction "BST") (pintype "output"))
  )
	(footprint "kria-k26-devboard-footprints:SOIC-4_W3.9mm" (layer "F.Cu")
    (at 177.79 70.21 180)
    (property "Author" "Antmicro")
    (property "License" "Apache-2.0")
    (property "MPN" "MB10S")
    (property "Manufacturer" "Multicomp Pro")
    (property "Sheetfile" "PoE.kicad_sch")
    (property "Sheetname" "PoE")
    (property "ki_description" "TVS diode")
    (property "ki_keywords" "SMT, DIODE, SEMICONDUCTOR, TVS, BRIDGE, RECTIFIER")
    (attr smd)
    (fp_text reference "D8" (at 3.48 -0.46 180) (layer "F.SilkS")
        (effects (font (size 0.7 0.7) (thickness 0.15)) (justify left bottom))
    )
    (fp_text value "MB10S" (at 0 3.6 180) (layer "F.Fab") hide
        (effects (font (size 0.7 0.7) (thickness 0.15)) (justify left bottom))
    )
    (fp_text user "Author: Antmicro" (at -4.111 6.546 180) (layer "F.Fab") hide
        (effects (font (size 0.7 0.7) (thickness 0.15)) (justify left bottom))
    )
    (fp_text user "${REFERENCE}" (at -4.111 5.347 180) (layer "F.Fab") hide
        (effects (font (size 0.7 0.7) (thickness 0.15)) (justify left bottom))
    )
    (fp_text user "License: Apache-2.0" (at -4.111 7.746 180) (layer "F.Fab") hide
        (effects (font (size 0.7 0.7) (thickness 0.15)) (justify left bottom))
    )
    (fp_line (start -2.101 2.479) (end 2.1 2.479)
      (stroke (width 0.15) (type solid)) (layer "F.SilkS"))
    (fp_line (start -2.1 -2.5) (end 2.101 -2.5)
      (stroke (width 0.15) (type solid)) (layer "F.SilkS"))
    (fp_circle (center -2.55 -2) (end -2.451 -2)
      (stroke (width 0.15) (type solid)) (fill solid) (layer "F.SilkS"))
    (fp_rect (start -3.8 -2.7) (end 3.8 2.7)
      (stroke (width 0.05) (type solid)) (fill none) (layer "F.CrtYd"))
    (fp_line (start -2.101 -2.48) (end 2.1 -2.48)
      (stroke (width 0.15) (type solid)) (layer "F.Fab"))
    (fp_line (start -2.101 2.479) (end -2.101 -2.48)
      (stroke (width 0.15) (type solid)) (layer "F.Fab"))
    (fp_line (start 2.1 -2.48) (end 2.1 2.479)
      (stroke (width 0.15) (type solid)) (layer "F.Fab"))
    (fp_line (start 2.1 2.479) (end -2.101 2.479)
      (stroke (width 0.15) (type solid)) (layer "F.Fab"))
    (pad "1" smd roundrect (at -2.851 -1.226 180) (size 1.8 1) (layers "F.Cu" "F.Paste" "F.Mask") (roundrect_rratio 0.25)
      (net 9 "/Power Supply/PoE/VDD_POE_IN") (pinfunction "1") (pintype "passive"))
    (pad "2" smd roundrect (at -2.851 1.225 180) (size 1.8 1) (layers "F.Cu" "F.Paste" "F.Mask") (roundrect_rratio 0.25)
      (net 10 "/Power Supply/PoE/VSS_POE_IN") (pinfunction "2") (pintype "passive"))
    (pad "3" smd roundrect (at 2.85 1.225 180) (size 1.8 1) (layers "F.Cu" "F.Paste" "F.Mask") (roundrect_rratio 0.25)
      (net 236 "/Ethernet/POE_VC1") (pinfunction "3") (pintype "passive"))
    (pad "4" smd roundrect (at 2.85 -1.226 180) (size 1.8 1) (layers "F.Cu" "F.Paste" "F.Mask") (roundrect_rratio 0.25)
      (net 235 "/Ethernet/POE_VC2") (pinfunction "4") (pintype "passive"))
  )
	(footprint "kria-k26-devboard-footprints:DO-214AC" (layer "F.Cu")
    (at 184.125 73.9 -90)
    (property "Author" "Antmicro")
    (property "License" "Apache-2.0")
    (property "MPN" "SMAJ58A-13-F")
    (property "Manufacturer" "Diodes Incorporated")
    (property "Sheetfile" "PoE.kicad_sch")
    (property "Sheetname" "PoE")
    (attr smd)
    (fp_text reference "D10" (at 0 -2.05 -90) (layer "F.SilkS")
        (effects (font (size 0.7 0.7) (thickness 0.15)) (justify left bottom))
    )
    (fp_text value "SMAJ58A-13-F" (at 0 2.45 -90) (layer "F.Fab") hide
        (effects (font (size 0.7 0.7) (thickness 0.15)) (justify left bottom))
    )
    (fp_text user "Author: Antmicro" (at -3.301 5.65 -90) (layer "F.Fab") hide
        (effects (font (size 0.7 0.7) (thickness 0.15)) (justify left bottom))
    )
    (fp_text user "${REFERENCE}" (at -3.301 4.45 -90) (layer "F.Fab") hide
        (effects (font (size 0.7 0.7) (thickness 0.15)) (justify left bottom))
    )
    (fp_text user "License: Apache-2.0" (at -3.301 6.85 -90) (layer "F.Fab") hide
        (effects (font (size 0.7 0.7) (thickness 0.15)) (justify left bottom))
    )
    (fp_line (start -0.9 1.3) (end -0.9 -1.3)
      (stroke (width 0.15) (type solid)) (layer "F.SilkS"))
    (fp_rect (start -3.25 -1.55) (end 3.25 1.55)
      (stroke (width 0.05) (type solid)) (fill none) (layer "F.CrtYd"))
    (fp_line (start -2.15 -1.301) (end -2.15 1.3)
      (stroke (width 0.15) (type solid)) (layer "F.Fab"))
    (fp_line (start -2.15 -1.301) (end 2.148 -1.301)
      (stroke (width 0.15) (type solid)) (layer "F.Fab"))
    (fp_line (start -2.15 1.3) (end 2.148 1.3)
      (stroke (width 0.15) (type solid)) (layer "F.Fab"))
    (fp_line (start -1.442 1.3) (end -1.365 1.3)
      (stroke (width 0.15) (type solid)) (layer "F.Fab"))
    (fp_line (start -1.363 -1.301) (end -1.442 -1.301)
      (stroke (width 0.15) (type solid)) (layer "F.Fab"))
    (fp_line (start 2.148 -1.301) (end 2.148 1.3)
      (stroke (width 0.15) (type solid)) (layer "F.Fab"))
    (fp_rect (start -1.363 -1.301) (end -1.1 1.3)
      (stroke (width 0.15) (type solid)) (fill solid) (layer "F.Fab"))
    (pad "A" smd roundrect (at 1.999 0 270) (size 2 2.1) (layers "F.Cu" "F.Paste" "F.Mask") (roundrect_rratio 0.1)
      (net 10 "/Power Supply/PoE/VSS_POE_IN") (pinfunction "A") (pintype "passive"))
    (pad "K" smd roundrect (at -2 0 270) (size 2 2.1) (layers "F.Cu" "F.Paste" "F.Mask") (roundrect_rratio 0.1)
      (net 9 "/Power Supply/PoE/VDD_POE_IN") (pinfunction "K") (pintype "passive"))
  )
	(footprint "kria-k26-devboard-footprints:C_0805_2012Metric" (layer "F.Cu")
    (at 187.1766 72.904773 -90)
    (descr "Capacitor SMD 0805")
    (tags "capacitor SMD 0805")
    (property "Author" "Antmicro")
    (property "Dielectric" "X7R")
    (property "License" "Apache-2.0")
    (property "MPN" "CL21B104KCFNNNE")
    (property "Manufacturer" "SAMSUNG")
    (property "Sheetfile" "PoE.kicad_sch")
    (property "Sheetname" "PoE")
    (property "Val" "100n/100V")
    (property "Voltage" "100V")
    (property "ki_description" " ")
    (attr smd)
    (fp_text reference "C171" (at 1.855227 -1.7934 -90) (layer "F.SilkS")
        (effects (font (size 0.7 0.7) (thickness 0.15)) (justify left bottom))
    )
    (fp_text value "C_100n_0805_100V" (at 0 1.947 -90) (layer "F.Fab") hide
        (effects (font (size 0.7 0.7) (thickness 0.15)) (justify left bottom))
    )
    (fp_text user "${REFERENCE}" (at -1.9 3.947 -90) (layer "F.Fab") hide
        (effects (font (size 0.7 0.7) (thickness 0.15)) (justify left bottom))
    )
    (fp_text user "Author: Antmicro" (at -1.9 5.947 -90) (layer "F.Fab") hide
        (effects (font (size 0.7 0.7) (thickness 0.15)) (justify left bottom))
    )
    (fp_text user "License: Apache-2.0" (at -1.9 4.947 -90) (layer "F.Fab") hide
        (effects (font (size 0.7 0.7) (thickness 0.15)) (justify left bottom))
    )
    (fp_line (start -0.3 -0.8) (end 0.3 -0.8)
      (stroke (width 0.15) (type solid)) (layer "F.SilkS"))
    (fp_line (start -0.3 0.8) (end 0.3 0.8)
      (stroke (width 0.15) (type solid)) (layer "F.SilkS"))
    (fp_rect (start -1.9 -0.93) (end 1.9 0.93)
      (stroke (width 0.05) (type solid)) (fill none) (layer "F.CrtYd"))
    (fp_rect (start -0.95 -0.675) (end 0.95 0.675)
      (stroke (width 0.15) (type solid)) (fill none) (layer "F.Fab"))
    (pad "1" smd rect (at -1.05 0 270) (size 1.2 1.2) (layers "F.Cu" "F.Paste" "F.Mask")
      (net 9 "/Power Supply/PoE/VDD_POE_IN") (pintype "passive"))
    (pad "2" smd rect (at 1.05 0 270) (size 1.2 1.2) (layers "F.Cu" "F.Paste" "F.Mask")
      (net 10 "/Power Supply/PoE/VSS_POE_IN") (pintype "passive"))
  )
	(footprint "kria-k26-devboard-footprints:R_0402_1005Metric" (layer "F.Cu")
    (at 141.785 89.2 180)
    (descr "Resistor SMD 0402")
    (tags "resistor SMD 0402")
    (property "Author" "Antmicro")
    (property "License" "Apache-2.0")
    (property "MPN" "CR0402-FX-4701GLF")
    (property "Manufacturer" "Bourns")
    (property "Sheetfile" "eth.kicad_sch")
    (property "Sheetname" "Ethernet")
    (property "Tolerance" "1%")
    (property "Val" "4k7")
    (property "ki_description" "4k7 resistor in 0402 package with 1% tolerance")
    (attr smd)
    (fp_text reference "R74" (at 2.995 -0.41 180) (layer "F.SilkS")
        (effects (font (size 0.7 0.7) (thickness 0.15)) (justify left bottom))
    )
    (fp_text value "R_4k7_0402" (at 0 1.4 180) (layer "F.Fab") hide
        (effects (font (size 0.7 0.7) (thickness 0.15)) (justify left bottom))
    )
    (fp_text user "Author: Antmicro" (at -0.95 4.169 180) (layer "F.Fab") hide
        (effects (font (size 0.7 0.7) (thickness 0.15)) (justify left bottom))
    )
    (fp_text user "License: Apache-2.0" (at -0.95 5.169 180) (layer "F.Fab") hide
        (effects (font (size 0.7 0.7) (thickness 0.15)) (justify left bottom))
    )
    (fp_text user "${REFERENCE}" (at -0.95 3.168 180) (layer "F.Fab") hide
        (effects (font (size 0.7 0.7) (thickness 0.15)) (justify left bottom))
    )
    (fp_rect (start -0.93 -0.47) (end 0.93 0.47)
      (stroke (width 0.05) (type solid)) (fill none) (layer "F.CrtYd"))
    (fp_rect (start -0.5 -0.25) (end 0.5 0.25)
      (stroke (width 0.15) (type solid)) (fill none) (layer "F.Fab"))
    (pad "1" smd roundrect (at -0.485 0 180) (size 0.59 0.64) (layers "F.Cu" "F.Paste" "F.Mask") (roundrect_rratio 0.25)
      (net 673 "Net-(U30-JTAG_CLK)") (pintype "passive"))
    (pad "2" smd roundrect (at 0.485 0 180) (size 0.59 0.64) (layers "F.Cu" "F.Paste" "F.Mask") (roundrect_rratio 0.25)
      (net 17 "PS_1V8") (pintype "passive"))
  )
	(footprint "kria-k26-devboard-footprints:C_0402_1005Metric" (layer "F.Cu")
    (at 140.925 86.358222 -90)
    (descr "Capacitor SMD 0402")
    (tags "capacitor SMD 0402")
    (property "Author" "Antmicro")
    (property "Dielectric" "X5R")
    (property "License" "Apache-2.0")
    (property "MPN" "GRM155R61H104KE14D")
    (property "Manufacturer" "Murata")
    (property "Sheetfile" "eth.kicad_sch")
    (property "Sheetname" "Ethernet")
    (property "Val" "100n")
    (property "Voltage" "50V")
    (property "ki_description" " ")
    (attr smd)
    (fp_text reference "C104" (at 1.291778 0.675 -90) (layer "F.SilkS")
        (effects (font (size 0.7 0.7) (thickness 0.15)) (justify left bottom))
    )
    (fp_text value "C_100n_0402" (at 0 1.4 -90) (layer "F.Fab") hide
        (effects (font (size 0.7 0.7) (thickness 0.15)) (justify left bottom))
    )
    (fp_text user "${REFERENCE}" (at -0.932 3.168 -90) (layer "F.Fab") hide
        (effects (font (size 0.7 0.7) (thickness 0.15)) (justify left bottom))
    )
    (fp_text user "License: Apache-2.0" (at -0.932 5.17 -90) (layer "F.Fab") hide
        (effects (font (size 0.7 0.7) (thickness 0.15)) (justify left bottom))
    )
    (fp_text user "Author: Antmicro" (at -0.932 4.17 -90) (layer "F.Fab") hide
        (effects (font (size 0.7 0.7) (thickness 0.15)) (justify left bottom))
    )
    (fp_rect (start -0.94 -0.47) (end 0.94 0.47)
      (stroke (width 0.05) (type solid)) (fill none) (layer "F.CrtYd"))
    (fp_rect (start -0.499 -0.249) (end 0.499 0.249)
      (stroke (width 0.15) (type solid)) (fill none) (layer "F.Fab"))
    (pad "1" smd roundrect (at -0.484 0 270) (size 0.59 0.64) (layers "F.Cu" "F.Paste" "F.Mask") (roundrect_rratio 0.25)
      (net 17 "PS_1V8") (pintype "passive"))
    (pad "2" smd roundrect (at 0.484 0 270) (size 0.59 0.64) (layers "F.Cu" "F.Paste" "F.Mask") (roundrect_rratio 0.25)
      (net 1 "GND") (pintype "passive"))
  )
	(footprint "kria-k26-devboard-footprints:R_0402_1005Metric" (layer "F.Cu")
    (at 141.787154 88.19 180)
    (descr "Resistor SMD 0402")
    (tags "resistor SMD 0402")
    (property "Author" "Antmicro")
    (property "License" "Apache-2.0")
    (property "MPN" "CR0402-FX-2201GLF")
    (property "Manufacturer" "Bourns")
    (property "Sheetfile" "eth.kicad_sch")
    (property "Sheetname" "Ethernet")
    (property "Tolerance" "1%")
    (property "Val" "2k2")
    (property "ki_description" "2k2 resistor in 0402 package with 1% tolerance")
    (attr smd)
    (fp_text reference "R76" (at 2.995 -0.41 180) (layer "F.SilkS")
        (effects (font (size 0.7 0.7) (thickness 0.15)) (justify left bottom))
    )
    (fp_text value "R_2k2_0402" (at 0 1.4 180) (layer "F.Fab") hide
        (effects (font (size 0.7 0.7) (thickness 0.15)) (justify left bottom))
    )
    (fp_text user "License: Apache-2.0" (at -0.95 5.169 180) (layer "F.Fab") hide
        (effects (font (size 0.7 0.7) (thickness 0.15)) (justify left bottom))
    )
    (fp_text user "${REFERENCE}" (at -0.95 3.168 180) (layer "F.Fab") hide
        (effects (font (size 0.7 0.7) (thickness 0.15)) (justify left bottom))
    )
    (fp_text user "Author: Antmicro" (at -0.95 4.169 180) (layer "F.Fab") hide
        (effects (font (size 0.7 0.7) (thickness 0.15)) (justify left bottom))
    )
    (fp_rect (start -0.93 -0.47) (end 0.93 0.47)
      (stroke (width 0.05) (type solid)) (fill none) (layer "F.CrtYd"))
    (fp_rect (start -0.5 -0.25) (end 0.5 0.25)
      (stroke (width 0.15) (type solid)) (fill none) (layer "F.Fab"))
    (pad "1" smd roundrect (at -0.485 0 180) (size 0.59 0.64) (layers "F.Cu" "F.Paste" "F.Mask") (roundrect_rratio 0.25)
      (net 50 "/Ethernet/MIO77") (pintype "passive"))
    (pad "2" smd roundrect (at 0.485 0 180) (size 0.59 0.64) (layers "F.Cu" "F.Paste" "F.Mask") (roundrect_rratio 0.25)
      (net 17 "PS_1V8") (pintype "passive"))
  )
	(footprint "kria-k26-devboard-footprints:R_0402_1005Metric" (layer "F.Cu")
    (at 141.775 91.21 180)
    (descr "Resistor SMD 0402")
    (tags "resistor SMD 0402")
    (property "Author" "Antmicro")
    (property "License" "Apache-2.0")
    (property "MPN" "CR0402-FX-4701GLF")
    (property "Manufacturer" "Bourns")
    (property "Sheetfile" "eth.kicad_sch")
    (property "Sheetname" "Ethernet")
    (property "Tolerance" "1%")
    (property "Val" "4k7")
    (property "ki_description" "4k7 resistor in 0402 package with 1% tolerance")
    (attr smd)
    (fp_text reference "R73" (at 2.995 -0.41 180) (layer "F.SilkS")
        (effects (font (size 0.7 0.7) (thickness 0.15)) (justify left bottom))
    )
    (fp_text value "R_4k7_0402" (at 0 1.4 180) (layer "F.Fab") hide
        (effects (font (size 0.7 0.7) (thickness 0.15)) (justify left bottom))
    )
    (fp_text user "Author: Antmicro" (at -0.95 4.169 180) (layer "F.Fab") hide
        (effects (font (size 0.7 0.7) (thickness 0.15)) (justify left bottom))
    )
    (fp_text user "License: Apache-2.0" (at -0.95 5.169 180) (layer "F.Fab") hide
        (effects (font (size 0.7 0.7) (thickness 0.15)) (justify left bottom))
    )
    (fp_text user "${REFERENCE}" (at -0.95 3.168 180) (layer "F.Fab") hide
        (effects (font (size 0.7 0.7) (thickness 0.15)) (justify left bottom))
    )
    (fp_rect (start -0.93 -0.47) (end 0.93 0.47)
      (stroke (width 0.05) (type solid)) (fill none) (layer "F.CrtYd"))
    (fp_rect (start -0.5 -0.25) (end 0.5 0.25)
      (stroke (width 0.15) (type solid)) (fill none) (layer "F.Fab"))
    (pad "1" smd roundrect (at -0.485 0 180) (size 0.59 0.64) (layers "F.Cu" "F.Paste" "F.Mask") (roundrect_rratio 0.25)
      (net 672 "Net-(U30-JTAG_TDI)") (pintype "passive"))
    (pad "2" smd roundrect (at 0.485 0 180) (size 0.59 0.64) (layers "F.Cu" "F.Paste" "F.Mask") (roundrect_rratio 0.25)
      (net 17 "PS_1V8") (pintype "passive"))
  )
)
